(kicad_pcb
	(version 20241229)
	(generator "pcbnew")
	(generator_version "9.0")
	(general
		(thickness 1.711)
		(legacy_teardrops no)
	)
	(paper "A4")
	(title_block
		(title "Antmicro Baseboard for Jetson AGX Thor")
		(date "2026-02-18")
		(rev "1.1.0")
		(company "Antmicro Ltd")
		(comment 1 "www.antmicro.com")
		(comment 9 "footprint 110 of 1170 (J1), pads 1-80 of 699")
	)
	(layers
		(0 "F.Cu" signal)
		(4 "In1.Cu" signal)
		(6 "In2.Cu" signal)
		(8 "In3.Cu" signal)
		(10 "In4.Cu" jumper)
		(12 "In5.Cu" signal)
		(14 "In6.Cu" signal)
		(16 "In7.Cu" signal)
		(18 "In8.Cu" signal)
		(2 "B.Cu" signal)
		(9 "F.Adhes" user "F.Adhesive")
		(11 "B.Adhes" user "B.Adhesive")
		(13 "F.Paste" user)
		(15 "B.Paste" user)
		(5 "F.SilkS" user "F.Silkscreen")
		(7 "B.SilkS" user "B.Silkscreen")
		(1 "F.Mask" user)
		(3 "B.Mask" user)
		(17 "Dwgs.User" user "User.Drawings")
		(19 "Cmts.User" user "User.Comments")
		(21 "Eco1.User" user "User.Eco1")
		(23 "Eco2.User" user "User.Eco2")
		(25 "Edge.Cuts" user)
		(27 "Margin" user)
		(31 "F.CrtYd" user "F.Courtyard")
		(29 "B.CrtYd" user "B.Courtyard")
		(35 "F.Fab" user)
		(33 "B.Fab" user)
	)
	(footprint "antmicro-footprints:Conn_Hermaphroditic_Molex_203456-0003_mirrored"
		(locked yes)
		(layer "F.Cu")
		(at 116.530532 78.15)
		(descr "Mirrored version of: https://www.molex.com/content/dam/molex/molex-dot-com/products/automated/en-us/salesdrawingpdf/203/203456/2034560003_sd.pdf")
		(property "Reference" "J1"
			(at -32.25 -11.2 180)
			(layer "F.SilkS")
			(effects
				(font
					(size 0.7 0.7)
					(thickness 0.15)
				)
				(justify right top)
			)
		)
		(property "Value" "Hermaphroditic_Molex_203456-0003_CUSTOM_Jetson_AGX_Thor_H8mm"
			(at 0.1 12.9 0)
			(layer "F.Fab")
			(effects
				(font
					(size 0.7 0.7)
					(thickness 0.15)
				)
				(justify right top)
			)
		)
		(property "Datasheet" "https://www.molex.com/content/dam/molex/molex-dot-com/products/automated/en-us/salesdrawingpdf/203/203456/2034560003_sd.pdf?inline"
			(at 0.1 0.2 0)
			(layer "F.Fab")
			(hide yes)
			(effects
				(font
					(size 0.7 0.7)
					(thickness 0.15)
				)
				(justify right top)
			)
		)
		(property "Description" "Mirror Mezz Hermaphroditic Connector, 5.50mm Connector Height, BGA-Attach Mounting, 7 Pair, 11 Row, 699 Circuits, 0.76µm Gold Plating, without Pegs"
			(at 0.1 0.2 0)
			(layer "F.Fab")
			(hide yes)
			(effects
				(font
					(size 0.7 0.7)
					(thickness 0.15)
				)
				(justify right top)
			)
		)
		(property "MPN" "203456-0003"
			(at 0 0 0)
			(unlocked yes)
			(layer "F.Fab")
			(hide yes)
			(effects
				(font
					(size 1 1)
					(thickness 0.15)
				)
			)
		)
		(property "Manufacturer" "Molex"
			(at 0 0 0)
			(unlocked yes)
			(layer "F.Fab")
			(hide yes)
			(effects
				(font
					(size 1 1)
					(thickness 0.15)
				)
			)
		)
		(property "Author" "Antmicro"
			(at 0 0 0)
			(unlocked yes)
			(layer "F.Fab")
			(hide yes)
			(effects
				(font
					(size 1 1)
					(thickness 0.15)
				)
			)
		)
		(property "License" "Apache-2.0"
			(at 0 0 0)
			(unlocked yes)
			(layer "F.Fab")
			(hide yes)
			(effects
				(font
					(size 1 1)
					(thickness 0.15)
				)
			)
		)
		(sheetname "/SoM_IO/")
		(sheetfile "som_io.kicad_sch")
		(solder_mask_margin 0.05)
		(attr smd)
		(pad "A3" smd circle
			(at -28.4 7.5 90)
			(size 0.5 0.5)
			(layers "F.Cu" "F.Mask" "F.Paste")
			(net 683 "/SoM_Power/~{SOM_PRSNT}")
			(pinfunction "PRSNT0")
			(pintype "passive")
		)
		(pad "A4" smd circle
			(at -27.5 7.5 90)
			(size 0.5 0.5)
			(layers "F.Cu" "F.Mask" "F.Paste")
			(net 873 "unconnected-(J1I-FSI_GPIO32-PadA4)")
			(pinfunction "FSI_GPIO32")
			(pintype "bidirectional+no_connect")
		)
		(pad "A5" smd circle
			(at -26.6 7.5 90)
			(size 0.5 0.5)
			(layers "F.Cu" "F.Mask" "F.Paste")
			(net 877 "unconnected-(J1I-FSI_GPIO34-PadA5)")
			(pinfunction "FSI_GPIO34")
			(pintype "bidirectional+no_connect")
		)
		(pad "A6" smd circle
			(at -25.7 7.5 90)
			(size 0.5 0.5)
			(layers "F.Cu" "F.Mask" "F.Paste")
			(net 563 "Net-(J1A-UFS0_REF_CLK)")
			(pinfunction "UFS0_REF_CLK")
			(pintype "passive")
		)
		(pad "A7" smd circle
			(at -24.8 7.5 90)
			(size 0.5 0.5)
			(layers "F.Cu" "F.Mask" "F.Paste")
			(net 759 "unconnected-(J1H-GPIO29-PadA7)")
			(pinfunction "GPIO29")
			(pintype "bidirectional+no_connect")
		)
		(pad "A8" smd circle
			(at -23.9 7.5 90)
			(size 0.5 0.5)
			(layers "F.Cu" "F.Mask" "F.Paste")
			(net 104 "/M.2/~{PEWAKE}")
			(pinfunction "PEX_WAKE_N")
			(pintype "input")
		)
		(pad "A9" smd circle
			(at -23 7.5 90)
			(size 0.5 0.5)
			(layers "F.Cu" "F.Mask" "F.Paste")
			(net 1 "GND")
			(pinfunction "GND")
			(pintype "passive")
		)
		(pad "A10" smd circle
			(at -22.1 7.5 90)
			(size 0.5 0.5)
			(layers "F.Cu" "F.Mask" "F.Paste")
			(net 492 "/SoM_IO2/USB2.D+")
			(pinfunction "USB2_P")
			(pintype "bidirectional")
		)
		(pad "A11" smd circle
			(at -21.2 7.5 90)
			(size 0.5 0.5)
			(layers "F.Cu" "F.Mask" "F.Paste")
			(net 493 "/SoM_IO2/USB2.D-")
			(pinfunction "USB2_N")
			(pintype "bidirectional")
		)
		(pad "A12" smd circle
			(at -20.3 7.5 90)
			(size 0.5 0.5)
			(layers "F.Cu" "F.Mask" "F.Paste")
			(net 1 "GND")
			(pinfunction "GND")
			(pintype "passive")
		)
		(pad "A13" smd circle
			(at -19 7.5 90)
			(size 0.5 0.5)
			(layers "F.Cu" "F.Mask" "F.Paste")
			(net 1 "GND")
			(pinfunction "GND")
			(pintype "passive")
		)
		(pad "A14" smd circle
			(at -18.1 7.5 90)
			(size 0.5 0.5)
			(layers "F.Cu" "F.Mask" "F.Paste")
			(net 1258 "/SoM_IO2/DP2.TX0_C-")
			(pinfunction "DP2_D0_HDMI_D2_N")
			(pintype "output")
		)
		(pad "A15" smd circle
			(at -17.2 7.5 90)
			(size 0.5 0.5)
			(layers "F.Cu" "F.Mask" "F.Paste")
			(net 1254 "/SoM_IO2/DP2.TX0_C+")
			(pinfunction "DP2_D0_HDMI_D2_P")
			(pintype "output")
		)
		(pad "A16" smd circle
			(at -16.3 7.5 90)
			(size 0.5 0.5)
			(layers "F.Cu" "F.Mask" "F.Paste")
			(net 1 "GND")
			(pinfunction "GND")
			(pintype "passive")
		)
		(pad "A17" smd circle
			(at -15 7.5 90)
			(size 0.5 0.5)
			(layers "F.Cu" "F.Mask" "F.Paste")
			(net 1 "GND")
			(pinfunction "GND")
			(pintype "passive")
		)
		(pad "A18" smd circle
			(at -14.1 7.5 90)
			(size 0.5 0.5)
			(layers "F.Cu" "F.Mask" "F.Paste")
			(net 625 "/SoM_IO/SFP_LEDY_1V8")
			(pinfunction "GPIO34")
			(pintype "passive")
		)
		(pad "A19" smd circle
			(at -13.2 7.5 90)
			(size 0.5 0.5)
			(layers "F.Cu" "F.Mask" "F.Paste")
			(net 789 "/Expansion connector/DP2.HPD")
			(pinfunction "HPD2")
			(pintype "bidirectional")
		)
		(pad "A20" smd circle
			(at -12.3 7.5 90)
			(size 0.5 0.5)
			(layers "F.Cu" "F.Mask" "F.Paste")
			(net 1 "GND")
			(pinfunction "GND")
			(pintype "passive")
		)
		(pad "A21" smd circle
			(at -11 7.5 90)
			(size 0.5 0.5)
			(layers "F.Cu" "F.Mask" "F.Paste")
			(net 1 "GND")
			(pinfunction "GND")
			(pintype "passive")
		)
		(pad "A22" smd circle
			(at -10.1 7.5 90)
			(size 0.5 0.5)
			(layers "F.Cu" "F.Mask" "F.Paste")
			(net 299 "/SoM_IO2/USBSS1.RX+")
			(pinfunction "UPHY_RX1_P")
			(pintype "input")
		)
		(pad "A23" smd circle
			(at -9.2 7.5 90)
			(size 0.5 0.5)
			(layers "F.Cu" "F.Mask" "F.Paste")
			(net 324 "/SoM_IO2/USBSS1.RX-")
			(pinfunction "UPHY_RX1_N")
			(pintype "input")
		)
		(pad "A24" smd circle
			(at -8.3 7.5 90)
			(size 0.5 0.5)
			(layers "F.Cu" "F.Mask" "F.Paste")
			(net 1 "GND")
			(pinfunction "GND")
			(pintype "passive")
		)
		(pad "A25" smd circle
			(at -7 7.5 90)
			(size 0.5 0.5)
			(layers "F.Cu" "F.Mask" "F.Paste")
			(net 1 "GND")
			(pinfunction "GND")
			(pintype "passive")
		)
		(pad "A26" smd circle
			(at -6.1 7.5 90)
			(size 0.5 0.5)
			(layers "F.Cu" "F.Mask" "F.Paste")
			(net 681 "/M.2/PCIe_{C5x4}.RX3+")
			(pinfunction "UPHY_RX11_P")
			(pintype "input")
		)
		(pad "A27" smd circle
			(at -5.2 7.5 90)
			(size 0.5 0.5)
			(layers "F.Cu" "F.Mask" "F.Paste")
			(net 564 "/M.2/PCIe_{C5x4}.RX3-")
			(pinfunction "UPHY_RX11_N")
			(pintype "input")
		)
		(pad "A28" smd circle
			(at -4.3 7.5 90)
			(size 0.5 0.5)
			(layers "F.Cu" "F.Mask" "F.Paste")
			(net 1 "GND")
			(pinfunction "GND")
			(pintype "passive")
		)
		(pad "A29" smd circle
			(at -3 7.5 90)
			(size 0.5 0.5)
			(layers "F.Cu" "F.Mask" "F.Paste")
			(net 1 "GND")
			(pinfunction "GND")
			(pintype "passive")
		)
		(pad "A30" smd circle
			(at -2.1 7.5 90)
			(size 0.5 0.5)
			(layers "F.Cu" "F.Mask" "F.Paste")
			(net 772 "unconnected-(J1B-UPHY_RX15_P-PadA30)")
			(pinfunction "UPHY_RX15_P")
			(pintype "input+no_connect")
		)
		(pad "A31" smd circle
			(at -1.2 7.5 90)
			(size 0.5 0.5)
			(layers "F.Cu" "F.Mask" "F.Paste")
			(net 695 "unconnected-(J1B-UPHY_RX15_N-PadA31)")
			(pinfunction "UPHY_RX15_N")
			(pintype "input+no_connect")
		)
		(pad "A32" smd circle
			(at -0.3 7.5 90)
			(size 0.5 0.5)
			(layers "F.Cu" "F.Mask" "F.Paste")
			(net 1 "GND")
			(pinfunction "GND")
			(pintype "passive")
		)
		(pad "A33" smd circle
			(at 1 7.5 90)
			(size 0.5 0.5)
			(layers "F.Cu" "F.Mask" "F.Paste")
			(net 1 "GND")
			(pinfunction "GND")
			(pintype "passive")
		)
		(pad "A34" smd circle
			(at 1.9 7.5 90)
			(size 0.5 0.5)
			(layers "F.Cu" "F.Mask" "F.Paste")
			(net 1266 "/SoM_IO2/DP3.TX2_C+")
			(pinfunction "DP3_D2_HDMI_D0_P")
			(pintype "output")
		)
		(pad "A35" smd circle
			(at 2.8 7.5 90)
			(size 0.5 0.5)
			(layers "F.Cu" "F.Mask" "F.Paste")
			(net 1270 "/SoM_IO2/DP3.TX2_C-")
			(pinfunction "DP3_D2_HDMI_D0_N")
			(pintype "output")
		)
		(pad "A36" smd circle
			(at 3.7 7.5 90)
			(size 0.5 0.5)
			(layers "F.Cu" "F.Mask" "F.Paste")
			(net 1 "GND")
			(pinfunction "GND")
			(pintype "passive")
		)
		(pad "A37" smd circle
			(at 5 7.5 90)
			(size 0.5 0.5)
			(layers "F.Cu" "F.Mask" "F.Paste")
			(net 1 "GND")
			(pinfunction "GND")
			(pintype "passive")
		)
		(pad "A38" smd circle
			(at 5.9 7.5 90)
			(size 0.5 0.5)
			(layers "F.Cu" "F.Mask" "F.Paste")
			(net 1289 "unconnected-(J1K-GPIO43-PadA38)")
			(pinfunction "GPIO43")
			(pintype "passive+no_connect")
		)
		(pad "A39" smd circle
			(at 6.8 7.5 90)
			(size 0.5 0.5)
			(layers "F.Cu" "F.Mask" "F.Paste")
			(net 1291 "unconnected-(J1K-GPIO37-PadA39)")
			(pinfunction "GPIO37")
			(pintype "passive+no_connect")
		)
		(pad "A40" smd circle
			(at 7.7 7.5 90)
			(size 0.5 0.5)
			(layers "F.Cu" "F.Mask" "F.Paste")
			(net 1 "GND")
			(pinfunction "GND")
			(pintype "passive")
		)
		(pad "A41" smd circle
			(at 8.6 7.5 90)
			(size 0.5 0.5)
			(layers "F.Cu" "F.Mask" "F.Paste")
			(net 88 "/CSI/CAM0.CSI2_D0+")
			(pinfunction "CSI2_D0_P")
			(pintype "input")
		)
		(pad "A42" smd circle
			(at 9.5 7.5 90)
			(size 0.5 0.5)
			(layers "F.Cu" "F.Mask" "F.Paste")
			(net 64 "/CSI/CAM0.CSI2_D0-")
			(pinfunction "CSI2_D0_N")
			(pintype "input")
		)
		(pad "A43" smd circle
			(at 10.4 7.5 90)
			(size 0.5 0.5)
			(layers "F.Cu" "F.Mask" "F.Paste")
			(net 1 "GND")
			(pinfunction "GND")
			(pintype "passive")
		)
		(pad "A44" smd circle
			(at 11.3 7.5 90)
			(size 0.5 0.5)
			(layers "F.Cu" "F.Mask" "F.Paste")
			(net 124 "/CSI/CAM3.CSI7_D0+")
			(pinfunction "CSI7_D0_P")
			(pintype "input")
		)
		(pad "A45" smd circle
			(at 12.2 7.5 90)
			(size 0.5 0.5)
			(layers "F.Cu" "F.Mask" "F.Paste")
			(net 59 "/CSI/CAM3.CSI7_D0-")
			(pinfunction "CSI7_D0_N")
			(pintype "input")
		)
		(pad "A46" smd circle
			(at 13.1 7.5 90)
			(size 0.5 0.5)
			(layers "F.Cu" "F.Mask" "F.Paste")
			(net 1 "GND")
			(pinfunction "GND")
			(pintype "passive")
		)
		(pad "A47" smd circle
			(at 14 7.5 90)
			(size 0.5 0.5)
			(layers "F.Cu" "F.Mask" "F.Paste")
			(net 641 "unconnected-(J1D-I2C10_CLK-PadA47)")
			(pinfunction "I2C10_CLK")
			(pintype "bidirectional+no_connect")
		)
		(pad "A48" smd circle
			(at 14.9 7.5 90)
			(size 0.5 0.5)
			(layers "F.Cu" "F.Mask" "F.Paste")
			(net 671 "unconnected-(J1D-I2C10_DAT-PadA48)")
			(pinfunction "I2C10_DAT")
			(pintype "bidirectional+no_connect")
		)
		(pad "A49" smd circle
			(at 15.8 7.5 90)
			(size 0.5 0.5)
			(layers "F.Cu" "F.Mask" "F.Paste")
			(net 1 "GND")
			(pinfunction "GND")
			(pintype "passive")
		)
		(pad "A50" smd circle
			(at 16.7 7.5 90)
			(size 0.5 0.5)
			(layers "F.Cu" "F.Mask" "F.Paste")
			(net 617 "/SoM_IO2/DP0.TX2_C-")
			(pinfunction "DP0_D2_HDMI_D0_N")
			(pintype "output")
		)
		(pad "A51" smd circle
			(at 17.6 7.5 90)
			(size 0.5 0.5)
			(layers "F.Cu" "F.Mask" "F.Paste")
			(net 615 "/SoM_IO2/DP0.TX2_C+")
			(pinfunction "DP0_D2_HDMI_D0_P")
			(pintype "output")
		)
		(pad "A52" smd circle
			(at 18.5 7.5 90)
			(size 0.5 0.5)
			(layers "F.Cu" "F.Mask" "F.Paste")
			(net 1 "GND")
			(pinfunction "GND")
			(pintype "passive")
		)
		(pad "A53" smd circle
			(at 19.4 7.5 90)
			(size 0.5 0.5)
			(layers "F.Cu" "F.Mask" "F.Paste")
			(net 133 "/SoM_IO/I2C5_SCL_1V8")
			(pinfunction "I2C5_CLK")
			(pintype "bidirectional")
		)
		(pad "A54" smd circle
			(at 20.3 7.5 90)
			(size 0.5 0.5)
			(layers "F.Cu" "F.Mask" "F.Paste")
			(net 131 "/CSI/CAM_CTRL.VSYNC_CAM1")
			(pinfunction "GPIO46")
			(pintype "passive")
		)
		(pad "A55" smd circle
			(at 21.2 7.5 90)
			(size 0.5 0.5)
			(layers "F.Cu" "F.Mask" "F.Paste")
			(net 626 "unconnected-(J1D-I2C9_CLK-PadA55)")
			(pinfunction "I2C9_CLK")
			(pintype "bidirectional+no_connect")
		)
		(pad "A56" smd circle
			(at 22.1 7.5 90)
			(size 0.5 0.5)
			(layers "F.Cu" "F.Mask" "F.Paste")
			(net 69 "/Expansion connector/SPI1.MISO")
			(pinfunction "SPI1_MISO")
			(pintype "bidirectional")
		)
		(pad "A57" smd circle
			(at 23 7.5 90)
			(size 0.5 0.5)
			(layers "F.Cu" "F.Mask" "F.Paste")
			(net 158 "/Expansion connector/UART2.CTS")
			(pinfunction "UART2_CTS")
			(pintype "input")
		)
		(pad "A58" smd circle
			(at 23.9 7.5 90)
			(size 0.5 0.5)
			(layers "F.Cu" "F.Mask" "F.Paste")
			(net 878 "/SoM_IO/M2_E_W_DIS_2_1V8")
			(pinfunction "GPIO20")
			(pintype "passive")
		)
		(pad "A59" smd circle
			(at 24.8 7.5 90)
			(size 0.5 0.5)
			(layers "F.Cu" "F.Mask" "F.Paste")
			(net 487 "/Expansion connector/GPIO.USER_LED0")
			(pinfunction "GPIO05")
			(pintype "passive")
		)
		(pad "A60" smd circle
			(at 25.7 7.5 90)
			(size 0.5 0.5)
			(layers "F.Cu" "F.Mask" "F.Paste")
			(net 743 "/SoM_IO2/JTAG_TCK")
			(pinfunction "JTAG_TCK")
			(pintype "passive")
		)
		(pad "A61" smd circle
			(at 26.6 7.5 90)
			(size 0.5 0.5)
			(layers "F.Cu" "F.Mask" "F.Paste")
			(net 762 "Net-(J1A-SYSTEM_OC_N)")
			(pinfunction "SYSTEM_OC_N")
			(pintype "input")
		)
		(pad "A62" smd circle
			(at 27.5 7.5 90)
			(size 0.5 0.5)
			(layers "F.Cu" "F.Mask" "F.Paste")
			(net 1288 "unconnected-(J1K-GPIO17-PadA62)")
			(pinfunction "GPIO17")
			(pintype "passive+no_connect")
		)
		(pad "A63" smd circle
			(at 28.4 7.5 90)
			(size 0.5 0.5)
			(layers "F.Cu" "F.Mask" "F.Paste")
			(net 1 "GND")
			(pinfunction "GND")
			(pintype "passive")
		)
		(pad "B3" smd circle
			(at -28.2 6 90)
			(size 0.5 0.5)
			(layers "F.Cu" "F.Mask" "F.Paste")
			(net 12 "SYS_VIN_HV")
			(pinfunction "SYS_VIN_HV")
			(pintype "power_in")
		)
		(pad "B4" smd circle
			(at -27.3 6 90)
			(size 0.5 0.5)
			(layers "F.Cu" "F.Mask" "F.Paste")
			(net 1 "GND")
			(pinfunction "GND")
			(pintype "passive")
		)
		(pad "B5" smd circle
			(at -26.4 6 90)
			(size 0.5 0.5)
			(layers "F.Cu" "F.Mask" "F.Paste")
			(net 727 "unconnected-(J1G-FSI_GPIO26-PadB5)")
			(pinfunction "FSI_GPIO26")
			(pintype "passive+no_connect")
		)
		(pad "B6" smd circle
			(at -25.5 6 90)
			(size 0.5 0.5)
			(layers "F.Cu" "F.Mask" "F.Paste")
			(net 721 "unconnected-(J1I-FSI_GPIO30-PadB6)")
			(pinfunction "FSI_GPIO30")
			(pintype "passive+no_connect")
		)
		(pad "B7" smd circle
			(at -24.6 6 90)
			(size 0.5 0.5)
			(layers "F.Cu" "F.Mask" "F.Paste")
			(net 1 "GND")
			(pinfunction "GND")
			(pintype "passive")
		)
		(pad "B8" smd circle
			(at -23.7 6 90)
			(size 0.5 0.5)
			(layers "F.Cu" "F.Mask" "F.Paste")
			(net 764 "unconnected-(J1H-GPIO11-PadB8)")
			(pinfunction "GPIO11")
			(pintype "input+no_connect")
		)
		(pad "B9" smd circle
			(at -22.8 6 90)
			(size 0.5 0.5)
			(layers "F.Cu" "F.Mask" "F.Paste")
			(net 558 "unconnected-(J1G-FSI_GPIO20-PadB9)")
			(pinfunction "FSI_GPIO20")
			(pintype "input+no_connect")
		)
		(pad "B10" smd circle
			(at -21.9 6 90)
			(size 0.5 0.5)
			(layers "F.Cu" "F.Mask" "F.Paste")
			(net 795 "Net-(J1A-POWER_INT_N)")
			(pinfunction "POWER_INT_N")
			(pintype "input")
		)
		(pad "B11" smd circle
			(at -21 6 90)
			(size 0.5 0.5)
			(layers "F.Cu" "F.Mask" "F.Paste")
			(net 1 "GND")
			(pinfunction "GND")
			(pintype "passive")
		)
		(pad "B12" smd circle
			(at -20.1 6 90)
			(size 0.5 0.5)
			(layers "F.Cu" "F.Mask" "F.Paste")
			(net 797 "/Expansion connector/PCIe_{C3x2}.RX0+")
			(pinfunction "UPHY_RX6_P")
			(pintype "input")
		)
		(pad "B13" smd circle
			(at -19.2 6 90)
			(size 0.5 0.5)
			(layers "F.Cu" "F.Mask" "F.Paste")
			(net 752 "/Expansion connector/PCIe_{C3x2}.RX0-")
			(pinfunction "UPHY_RX6_N")
			(pintype "input")
		)
		(pad "B14" smd circle
			(at -18.3 6 90)
			(size 0.5 0.5)
			(layers "F.Cu" "F.Mask" "F.Paste")
			(net 1 "GND")
			(pinfunction "GND")
			(pintype "passive")
		)
		(pad "B15" smd circle
			(at -17 6 90)
			(size 0.5 0.5)
			(layers "F.Cu" "F.Mask" "F.Paste")
			(net 1 "GND")
			(pinfunction "GND")
			(pintype "passive")
		)
		(pad "B16" smd circle
			(at -16.1 6 90)
			(size 0.5 0.5)
			(layers "F.Cu" "F.Mask" "F.Paste")
			(net 651 "unconnected-(J1B-UPHY_RX16_P-PadB16)")
			(pinfunction "UPHY_RX16_P")
			(pintype "input+no_connect")
		)
		(pad "B17" smd circle
			(at -15.2 6 90)
			(size 0.5 0.5)
			(layers "F.Cu" "F.Mask" "F.Paste")
			(net 730 "unconnected-(J1B-UPHY_RX16_N-PadB17)")
			(pinfunction "UPHY_RX16_N")
			(pintype "input+no_connect")
		)
		(pad "B18" smd circle
			(at -14.3 6 90)
			(size 0.5 0.5)
			(layers "F.Cu" "F.Mask" "F.Paste")
			(net 1 "GND")
			(pinfunction "GND")
			(pintype "passive")
		)
		(pad "B19" smd circle
			(at -13 6 90)
			(size 0.5 0.5)
			(layers "F.Cu" "F.Mask" "F.Paste")
			(net 1 "GND")
			(pinfunction "GND")
			(pintype "passive")
		)
		(pad "B20" smd circle
			(at -12.1 6 90)
			(size 0.5 0.5)
			(layers "F.Cu" "F.Mask" "F.Paste")
			(net 637 "/Expansion connector/PCIe_{C2x1}.RX0-")
			(pinfunction "UPHY_RX4_N")
			(pintype "input")
		)
		(pad "B21" smd circle
			(at -11.2 6 90)
			(size 0.5 0.5)
			(layers "F.Cu" "F.Mask" "F.Paste")
			(net 790 "/Expansion connector/PCIe_{C2x1}.RX0+")
			(pinfunction "UPHY_RX4_P")
			(pintype "input")
		)
	)
)
